(kicad_pcb
	(version 20260206)
	(generator "pcbnew")
	(generator_version "10.0")
	(general
		(thickness 1.6)
		(legacy_teardrops no)
	)
	(paper "A4")
	(title_block
		(title "fcb — 12433-1M.1206WZS1330.brd")
		(comment 1 "Open Vault / Knox (Wiwynn) / footprint 326 of 495 (CN10), pads 1-56 of 56")
	)
	(layers
		(0 "F.Cu" signal "TOP")
		(4 "In1.Cu" signal "L2GND")
		(6 "In2.Cu" signal "L3VCC")
		(2 "B.Cu" signal "BOTTOM")
		(9 "F.Adhes" user "F.Adhesive")
		(11 "B.Adhes" user "B.Adhesive")
		(13 "F.Paste" user "Package Geometry/Pastemask Top")
		(15 "B.Paste" user "Package Geometry/Pastemask Bottom")
		(5 "F.SilkS" user "Ref Des/Silkscreen Top")
		(7 "B.SilkS" user "Ref Des/Silkscreen Bottom")
		(1 "F.Mask" user "Board Geometry/Soldermask Top")
		(3 "B.Mask" user "Board Geometry/Soldermask Bottom")
		(17 "Dwgs.User" user "User.Drawings")
		(19 "Cmts.User" user "User.Comments")
		(21 "Eco1.User" user "User.Eco1")
		(23 "Eco2.User" user "User.Eco2")
		(25 "Edge.Cuts" user "Board Geometry/Outline")
		(27 "Margin" user)
		(31 "F.CrtYd" user "Package Geometry/Place Bound Top")
		(29 "B.CrtYd" user "Package Geometry/Place Bound Bottom")
		(35 "F.Fab" user "Ref Des/Assembly Top")
		(33 "B.Fab" user "Ref Des/Assembly Bottom")
	)
	(footprint ""
		(layer "F.Cu")
		(at 37.999924 -56.999886 -90)
		(property "Reference" "CN10"
			(at 0 0 270)
			(layer "F.SilkS")
			(hide yes)
			(effects
				(font
					(size 1.27 1.27)
				)
			)
		)
		(property "Value" "FCI-CONN52-4R-1-GP"
			(at -30.89656 -6.096 270)
			(unlocked yes)
			(layer "F.Fab")
			(hide yes)
			(effects
				(font
					(size 1.016 1.016)
					(thickness 0.1524)
				)
			)
		)
		(property "Device Type" "51952-220LF"
			(at -30.89656 -7.62 270)
			(unlocked yes)
			(layer "F.Fab")
			(hide yes)
			(effects
				(font
					(size 1.016 1.016)
					(thickness 0.1524)
				)
			)
		)
		(duplicate_pad_numbers_are_jumpers no)
		(pad "" np_thru_hole circle
			(at -26.67 0 270)
			(size 0.254 0.254)
			(drill 3.2004)
			(layers "*.Cu" "*.Mask")
			(clearance 1.8288)
			(thermal_gap 1.8288)
		)
		(pad "" np_thru_hole circle
			(at -21.59 0 270)
			(size 0.254 0.254)
			(drill 2.5146)
			(layers "*.Cu" "*.Mask")
			(clearance 1.4859)
			(thermal_gap 1.4859)
		)
		(pad "" np_thru_hole circle
			(at 21.59 0 270)
			(size 0.254 0.254)
			(drill 2.5146)
			(layers "*.Cu" "*.Mask")
			(clearance 1.4859)
			(thermal_gap 1.4859)
		)
		(pad "" np_thru_hole circle
			(at 26.67 0 270)
			(size 0.254 0.254)
			(drill 3.2004)
			(layers "*.Cu" "*.Mask")
			(clearance 1.8288)
			(thermal_gap 1.8288)
		)
		(pad "A1" thru_hole circle
			(at -5.08 0 270)
			(size 1.4478 1.4478)
			(drill 1.0414)
			(layers "*.Cu" "*.Mask")
			(remove_unused_layers no)
			(net "I2C_C_SDA_CONN_R")
			(clearance 0.1524)
			(thermal_gap 0.1524)
		)
		(pad "A2" thru_hole circle
			(at -2.54 0 270)
			(size 1.4478 1.4478)
			(drill 1.0414)
			(layers "*.Cu" "*.Mask")
			(remove_unused_layers no)
			(net "GND")
			(clearance 0.1524)
			(thermal_gap 0.1524)
		)
		(pad "A3" thru_hole circle
			(at 0 0 270)
			(size 1.4478 1.4478)
			(drill 1.0414)
			(layers "*.Cu" "*.Mask")
			(remove_unused_layers no)
			(net "I2C_C_SCL_CONN_R")
			(clearance 0.1524)
			(thermal_gap 0.1524)
		)
		(pad "A4" thru_hole circle
			(at 2.54 0 270)
			(size 1.4478 1.4478)
			(drill 1.0414)
			(layers "*.Cu" "*.Mask")
			(remove_unused_layers no)
			(net "GND")
			(clearance 0.1524)
			(thermal_gap 0.1524)
		)
		(pad "A5" thru_hole circle
			(at 5.08 0 270)
			(size 1.4478 1.4478)
			(drill 1.0414)
			(layers "*.Cu" "*.Mask")
			(remove_unused_layers no)
			(net "PWM_EXP_2B")
			(clearance 0.1524)
			(thermal_gap 0.1524)
		)
		(pad "B1" thru_hole circle
			(at -5.08 -2.54 270)
			(size 1.4478 1.4478)
			(drill 1.0414)
			(layers "*.Cu" "*.Mask")
			(remove_unused_layers no)
			(net "GND")
			(clearance 0.1524)
			(thermal_gap 0.1524)
		)
		(pad "B2" thru_hole circle
			(at -2.54 -2.54 270)
			(size 1.4478 1.4478)
			(drill 1.0414)
			(layers "*.Cu" "*.Mask")
			(remove_unused_layers no)
			(net "PWM_EXP_2A")
			(clearance 0.1524)
			(thermal_gap 0.1524)
		)
		(pad "B3" thru_hole circle
			(at 0 -2.54 270)
			(size 1.4478 1.4478)
			(drill 1.0414)
			(layers "*.Cu" "*.Mask")
			(remove_unused_layers no)
			(net "GND")
			(clearance 0.1524)
			(thermal_gap 0.1524)
		)
		(pad "B4" thru_hole circle
			(at 2.54 -2.54 270)
			(size 1.4478 1.4478)
			(drill 1.0414)
			(layers "*.Cu" "*.Mask")
			(remove_unused_layers no)
			(net "SELF_2B_HB")
			(clearance 0.1524)
			(thermal_gap 0.1524)
		)
		(pad "B5" thru_hole circle
			(at 5.08 -2.54 270)
			(size 1.4478 1.4478)
			(drill 1.0414)
			(layers "*.Cu" "*.Mask")
			(remove_unused_layers no)
			(net "GND")
			(clearance 0.1524)
			(thermal_gap 0.1524)
		)
		(pad "C1" thru_hole circle
			(at -5.08 -5.08 270)
			(size 1.4478 1.4478)
			(drill 1.0414)
			(layers "*.Cu" "*.Mask")
			(remove_unused_layers no)
			(net "P12VL_2490_EN_1")
			(clearance 0.1524)
			(thermal_gap 0.1524)
		)
		(pad "C2" thru_hole circle
			(at -2.54 -5.08 270)
			(size 1.4478 1.4478)
			(drill 1.0414)
			(layers "*.Cu" "*.Mask")
			(remove_unused_layers no)
			(net "P12VL_2490_EN_2")
			(clearance 0.1524)
			(thermal_gap 0.1524)
		)
		(pad "C3" thru_hole circle
			(at 0 -5.08 270)
			(size 1.4478 1.4478)
			(drill 1.0414)
			(layers "*.Cu" "*.Mask")
			(remove_unused_layers no)
			(net "SELF_2A_HB")
			(clearance 0.1524)
			(thermal_gap 0.1524)
		)
		(pad "C4" thru_hole circle
			(at 2.54 -5.08 270)
			(size 1.4478 1.4478)
			(drill 1.0414)
			(layers "*.Cu" "*.Mask")
			(remove_unused_layers no)
			(net "SEB_PEER_2A_HB")
			(clearance 0.1524)
			(thermal_gap 0.1524)
		)
		(pad "C5" thru_hole circle
			(at 5.08 -5.08 270)
			(size 1.4478 1.4478)
			(drill 1.0414)
			(layers "*.Cu" "*.Mask")
			(remove_unused_layers no)
			(net "SEB_PEER_2B_HB")
			(clearance 0.1524)
			(thermal_gap 0.1524)
		)
		(pad "D1" thru_hole circle
			(at -5.08 -7.62 270)
			(size 1.4478 1.4478)
			(drill 1.0414)
			(layers "*.Cu" "*.Mask")
			(remove_unused_layers no)
			(net "PEER_TRAY PRESENT_LOWER")
			(clearance 0.1524)
			(thermal_gap 0.1524)
		)
		(pad "D2" thru_hole circle
			(at -2.54 -7.62 270)
			(size 1.4478 1.4478)
			(drill 1.0414)
			(layers "*.Cu" "*.Mask")
			(remove_unused_layers no)
			(net "LOWER_TRAY_ID")
			(clearance 0.1524)
			(thermal_gap 0.1524)
		)
		(pad "D3" thru_hole circle
			(at 0 -7.62 270)
			(size 1.4478 1.4478)
			(drill 1.0414)
			(layers "*.Cu" "*.Mask")
			(remove_unused_layers no)
			(net "FCB_HW_REVISION")
			(clearance 0.1524)
			(thermal_gap 0.1524)
		)
		(pad "D4" thru_hole circle
			(at 2.54 -7.62 270)
			(size 1.4478 1.4478)
			(drill 1.0414)
			(layers "*.Cu" "*.Mask")
			(remove_unused_layers no)
			(net "SD_LATCH_RELEASE_L")
			(clearance 0.1524)
			(thermal_gap 0.1524)
		)
		(pad "D5" thru_hole circle
			(at 5.08 -7.62 270)
			(size 1.4478 1.4478)
			(drill 1.0414)
			(layers "*.Cu" "*.Mask")
			(remove_unused_layers no)
			(net "SELF_TRAY_PRESENT_LOWER")
			(clearance 0.1524)
			(thermal_gap 0.1524)
		)
		(pad "P1_1" thru_hole circle
			(at -15.88008 0 270)
			(size 1.4478 1.4478)
			(drill 1.0414)
			(layers "*.Cu" "*.Mask")
			(remove_unused_layers no)
			(net "P12VL")
			(clearance 0.1524)
			(thermal_gap 0.1524)
		)
		(pad "P1_2" thru_hole circle
			(at -15.88008 -2.54 270)
			(size 1.4478 1.4478)
			(drill 1.0414)
			(layers "*.Cu" "*.Mask")
			(remove_unused_layers no)
			(net "P12VL")
			(clearance 0.1524)
			(thermal_gap 0.1524)
		)
		(pad "P1_3" thru_hole circle
			(at -15.88008 -5.08 270)
			(size 1.4478 1.4478)
			(drill 1.0414)
			(layers "*.Cu" "*.Mask")
			(remove_unused_layers no)
			(net "P12VL")
			(clearance 0.1524)
			(thermal_gap 0.1524)
		)
		(pad "P1_4" thru_hole circle
			(at -15.88008 -7.62 270)
			(size 1.4478 1.4478)
			(drill 1.0414)
			(layers "*.Cu" "*.Mask")
			(remove_unused_layers no)
			(net "P12VL")
			(clearance 0.1524)
			(thermal_gap 0.1524)
		)
		(pad "P1_5" thru_hole circle
			(at -13.34008 0 270)
			(size 1.4478 1.4478)
			(drill 1.0414)
			(layers "*.Cu" "*.Mask")
			(remove_unused_layers no)
			(net "P12VL")
			(clearance 0.1524)
			(thermal_gap 0.1524)
		)
		(pad "P1_6" thru_hole circle
			(at -13.34008 -2.54 270)
			(size 1.4478 1.4478)
			(drill 1.0414)
			(layers "*.Cu" "*.Mask")
			(remove_unused_layers no)
			(net "P12VL")
			(clearance 0.1524)
			(thermal_gap 0.1524)
		)
		(pad "P1_7" thru_hole circle
			(at -13.34008 -5.08 270)
			(size 1.4478 1.4478)
			(drill 1.0414)
			(layers "*.Cu" "*.Mask")
			(remove_unused_layers no)
			(net "P12VL")
			(clearance 0.1524)
			(thermal_gap 0.1524)
		)
		(pad "P1_8" thru_hole circle
			(at -13.34008 -7.62 270)
			(size 1.4478 1.4478)
			(drill 1.0414)
			(layers "*.Cu" "*.Mask")
			(remove_unused_layers no)
			(net "P12VL")
			(clearance 0.1524)
			(thermal_gap 0.1524)
		)
		(pad "P2_1" thru_hole circle
			(at -10.80008 0 270)
			(size 1.4478 1.4478)
			(drill 1.0414)
			(layers "*.Cu" "*.Mask")
			(remove_unused_layers no)
			(net "P12VL")
			(clearance 0.1524)
			(thermal_gap 0.1524)
		)
		(pad "P2_2" thru_hole circle
			(at -10.80008 -2.54 270)
			(size 1.4478 1.4478)
			(drill 1.0414)
			(layers "*.Cu" "*.Mask")
			(remove_unused_layers no)
			(net "P12VL")
			(clearance 0.1524)
			(thermal_gap 0.1524)
		)
		(pad "P2_3" thru_hole circle
			(at -10.80008 -5.08 270)
			(size 1.4478 1.4478)
			(drill 1.0414)
			(layers "*.Cu" "*.Mask")
			(remove_unused_layers no)
			(net "P12VL")
			(clearance 0.1524)
			(thermal_gap 0.1524)
		)
		(pad "P2_4" thru_hole circle
			(at -10.80008 -7.62 270)
			(size 1.4478 1.4478)
			(drill 1.0414)
			(layers "*.Cu" "*.Mask")
			(remove_unused_layers no)
			(net "P12VL")
			(clearance 0.1524)
			(thermal_gap 0.1524)
		)
		(pad "P2_5" thru_hole circle
			(at -8.26008 0 270)
			(size 1.4478 1.4478)
			(drill 1.0414)
			(layers "*.Cu" "*.Mask")
			(remove_unused_layers no)
			(net "P12VL")
			(clearance 0.1524)
			(thermal_gap 0.1524)
		)
		(pad "P2_6" thru_hole circle
			(at -8.26008 -2.54 270)
			(size 1.4478 1.4478)
			(drill 1.0414)
			(layers "*.Cu" "*.Mask")
			(remove_unused_layers no)
			(net "P12VL")
			(clearance 0.1524)
			(thermal_gap 0.1524)
		)
		(pad "P2_7" thru_hole circle
			(at -8.26008 -5.08 270)
			(size 1.4478 1.4478)
			(drill 1.0414)
			(layers "*.Cu" "*.Mask")
			(remove_unused_layers no)
			(net "P12VL")
			(clearance 0.1524)
			(thermal_gap 0.1524)
		)
		(pad "P2_8" thru_hole circle
			(at -8.26008 -7.62 270)
			(size 1.4478 1.4478)
			(drill 1.0414)
			(layers "*.Cu" "*.Mask")
			(remove_unused_layers no)
			(net "P12VL")
			(clearance 0.1524)
			(thermal_gap 0.1524)
		)
		(pad "P3_1" thru_hole circle
			(at 8.26008 0 270)
			(size 1.4478 1.4478)
			(drill 1.0414)
			(layers "*.Cu" "*.Mask")
			(remove_unused_layers no)
			(net "GND")
			(clearance 0.1524)
			(thermal_gap 0.1524)
		)
		(pad "P3_2" thru_hole circle
			(at 8.26008 -2.54 270)
			(size 1.4478 1.4478)
			(drill 1.0414)
			(layers "*.Cu" "*.Mask")
			(remove_unused_layers no)
			(net "GND")
			(clearance 0.1524)
			(thermal_gap 0.1524)
		)
		(pad "P3_3" thru_hole circle
			(at 8.26008 -5.08 270)
			(size 1.4478 1.4478)
			(drill 1.0414)
			(layers "*.Cu" "*.Mask")
			(remove_unused_layers no)
			(net "GND")
			(clearance 0.1524)
			(thermal_gap 0.1524)
		)
		(pad "P3_4" thru_hole circle
			(at 8.26008 -7.62 270)
			(size 1.4478 1.4478)
			(drill 1.0414)
			(layers "*.Cu" "*.Mask")
			(remove_unused_layers no)
			(net "GND")
			(clearance 0.1524)
			(thermal_gap 0.1524)
		)
		(pad "P3_5" thru_hole circle
			(at 10.80008 0 270)
			(size 1.4478 1.4478)
			(drill 1.0414)
			(layers "*.Cu" "*.Mask")
			(remove_unused_layers no)
			(net "GND")
			(clearance 0.1524)
			(thermal_gap 0.1524)
		)
		(pad "P3_6" thru_hole circle
			(at 10.80008 -2.54 270)
			(size 1.4478 1.4478)
			(drill 1.0414)
			(layers "*.Cu" "*.Mask")
			(remove_unused_layers no)
			(net "GND")
			(clearance 0.1524)
			(thermal_gap 0.1524)
		)
		(pad "P3_7" thru_hole circle
			(at 10.80008 -5.08 270)
			(size 1.4478 1.4478)
			(drill 1.0414)
			(layers "*.Cu" "*.Mask")
			(remove_unused_layers no)
			(net "GND")
			(clearance 0.1524)
			(thermal_gap 0.1524)
		)
		(pad "P3_8" thru_hole circle
			(at 10.80008 -7.62 270)
			(size 1.4478 1.4478)
			(drill 1.0414)
			(layers "*.Cu" "*.Mask")
			(remove_unused_layers no)
			(net "GND")
			(clearance 0.1524)
			(thermal_gap 0.1524)
		)
		(pad "P4_1" thru_hole circle
			(at 13.34008 0 270)
			(size 1.4478 1.4478)
			(drill 1.0414)
			(layers "*.Cu" "*.Mask")
			(remove_unused_layers no)
			(net "GND")
			(clearance 0.1524)
			(thermal_gap 0.1524)
		)
		(pad "P4_2" thru_hole circle
			(at 13.34008 -2.54 270)
			(size 1.4478 1.4478)
			(drill 1.0414)
			(layers "*.Cu" "*.Mask")
			(remove_unused_layers no)
			(net "GND")
			(clearance 0.1524)
			(thermal_gap 0.1524)
		)
		(pad "P4_3" thru_hole circle
			(at 13.34008 -5.08 270)
			(size 1.4478 1.4478)
			(drill 1.0414)
			(layers "*.Cu" "*.Mask")
			(remove_unused_layers no)
			(net "GND")
			(clearance 0.1524)
			(thermal_gap 0.1524)
		)
		(pad "P4_4" thru_hole circle
			(at 13.34008 -7.62 270)
			(size 1.4478 1.4478)
			(drill 1.0414)
			(layers "*.Cu" "*.Mask")
			(remove_unused_layers no)
			(net "GND")
			(clearance 0.1524)
			(thermal_gap 0.1524)
		)
		(pad "P4_5" thru_hole circle
			(at 15.88008 0 270)
			(size 1.4478 1.4478)
			(drill 1.0414)
			(layers "*.Cu" "*.Mask")
			(remove_unused_layers no)
			(net "GND")
			(clearance 0.1524)
			(thermal_gap 0.1524)
		)
		(pad "P4_6" thru_hole circle
			(at 15.88008 -2.54 270)
			(size 1.4478 1.4478)
			(drill 1.0414)
			(layers "*.Cu" "*.Mask")
			(remove_unused_layers no)
			(net "GND")
			(clearance 0.1524)
			(thermal_gap 0.1524)
		)
		(pad "P4_7" thru_hole circle
			(at 15.88008 -5.08 270)
			(size 1.4478 1.4478)
			(drill 1.0414)
			(layers "*.Cu" "*.Mask")
			(remove_unused_layers no)
			(net "GND")
			(clearance 0.1524)
			(thermal_gap 0.1524)
		)
		(pad "P4_8" thru_hole circle
			(at 15.88008 -7.62 270)
			(size 1.4478 1.4478)
			(drill 1.0414)
			(layers "*.Cu" "*.Mask")
			(remove_unused_layers no)
			(net "GND")
			(clearance 0.1524)
			(thermal_gap 0.1524)
		)
	)
)
